# BASEBOARD_FAB2 (Tioga Pass) — schematic netlist excerpt (pin names and nets, part order shuffled) for the footprints in the layout excerpt that follows; sources: Cadence DE-HDL packaged netlist, KiCad conversion of Wiwynn_Tioga_Pass_MB.brd

R4F6  RES  2.2 5% EMPTY  pkg 0402  page 233 : A = VR_PVPP_GHJ_SNUB ; B = GND

T1D19  TEST-PAD-12P-1-GP-U  pkg DISCRET-GB1  page 258
  DP  = L10_85OHM_10INCH_DP
  DN  = L10_85OHM_10INCH_DN
  GND(0)  = GND
  GND(1)  = GND
  GND(2)  = GND
  GND(3)  = GND
  GND(4)  = GND
  GND(5)  = GND
  GND(6)  = GND
  GND(7)  = GND
  GND(8)  = GND
  GND(9)  = GND

(kicad_pcb
	(version 20260206)
	(generator "pcbnew")
	(generator_version "10.0")
	(general
		(thickness 1.6)
		(legacy_teardrops no)
	)
	(paper "A4")
	(title_block
		(title "Wiwynn_Tioga_Pass_MB.brd")
		(comment 1 "Tioga Pass / footprints 1031-1032 of 4770")
	)
	(layers
		(0 "F.Cu" signal "TOP")
		(4 "In1.Cu" signal "L2GND")
		(6 "In2.Cu" signal "L3")
		(8 "In3.Cu" signal "L4GND")
		(10 "In4.Cu" signal "L5")
		(12 "In5.Cu" signal "L6GND")
		(14 "In6.Cu" signal "L7VCC")
		(16 "In7.Cu" signal "L8VCC")
		(18 "In8.Cu" signal "L9GND")
		(20 "In9.Cu" signal "L10")
		(22 "In10.Cu" signal "L11GND")
		(24 "In11.Cu" signal "L12")
		(26 "In12.Cu" signal "L13GND")
		(2 "B.Cu" signal "BOTTOM")
		(9 "F.Adhes" user "F.Adhesive")
		(11 "B.Adhes" user "B.Adhesive")
		(13 "F.Paste" user "Package Geometry/Pastemask Top")
		(15 "B.Paste" user "Package Geometry/Pastemask Bottom")
		(5 "F.SilkS" user "Ref Des/Silkscreen Top")
		(7 "B.SilkS" user "Ref Des/Silkscreen Bottom")
		(1 "F.Mask" user "Board Geometry/Soldermask Top")
		(3 "B.Mask" user "Board Geometry/Soldermask Bottom")
		(17 "Dwgs.User" user "User.Drawings")
		(19 "Cmts.User" user "User.Comments")
		(21 "Eco1.User" user "User.Eco1")
		(23 "Eco2.User" user "User.Eco2")
		(25 "Edge.Cuts" user "Board Geometry/Outline")
		(27 "Margin" user)
		(31 "F.CrtYd" user "Package Geometry/Place Bound Top")
		(29 "B.CrtYd" user "Package Geometry/Place Bound Bottom")
		(35 "F.Fab" user "Ref Des/Assembly Top")
		(33 "B.Fab" user "Ref Des/Assembly Bottom")
	)
	(footprint ""
		(layer "F.Cu")
		(at 316.3443 -164.9095 -90)
		(property "Reference" "T1D19"
			(at 0 0 270)
			(layer "F.SilkS")
			(hide yes)
			(effects
				(font
					(size 1.27 1.27)
				)
			)
		)
		(property "Value" "*"
			(at -3.4036 -4.46405 270)
			(unlocked yes)
			(layer "F.Fab")
			(hide yes)
			(effects
				(font
					(size 0.889 0.889)
					(thickness 0.1524)
				)
			)
		)
		(property "Device Type" "TEST-PAD-12P-1-GP-U_DISCRET-GBA"
			(at -3.4036 -5.98805 270)
			(unlocked yes)
			(layer "F.Fab")
			(hide yes)
			(effects
				(font
					(size 0.889 0.889)
					(thickness 0.1524)
				)
			)
		)
		(duplicate_pad_numbers_are_jumpers no)
		(fp_line
			(start -2.3876 3.4798)
			(end -2.3876 -4.826)
			(stroke
				(width 0.1524)
				(type default)
			)
			(layer "F.SilkS")
		)
		(fp_line
			(start 2.3622 3.4798)
			(end -2.3876 3.4798)
			(stroke
				(width 0.1524)
				(type default)
			)
			(layer "F.SilkS")
		)
		(fp_line
			(start -2.3876 -4.826)
			(end 2.3622 -4.826)
			(stroke
				(width 0.1524)
				(type default)
			)
			(layer "F.SilkS")
		)
		(fp_line
			(start 2.3622 -4.826)
			(end 2.3622 3.4798)
			(stroke
				(width 0.1524)
				(type default)
			)
			(layer "F.SilkS")
		)
		(fp_rect
			(start -2.6416 3.7338)
			(end 2.6162 -5.08)
			(stroke
				(width 0)
				(type default)
			)
			(fill no)
			(layer "F.CrtYd")
		)
		(fp_rect
			(start -2.6416 3.7338)
			(end 2.6162 -5.08)
			(stroke
				(width 0)
				(type default)
			)
			(fill no)
			(layer "F.Fab")
		)
		(pad "1" smd circle
			(at 0.496824 -1.301496 270)
			(size 0.6604 0.6604)
			(layers "F.Cu" "F.Mask" "F.Paste")
			(net "L10_85OHM_10INCH_DP")
		)
		(pad "2" smd circle
			(at -0.503936 -1.301496 270)
			(size 0.6604 0.6604)
			(layers "F.Cu" "F.Mask" "F.Paste")
			(net "L10_85OHM_10INCH_DN")
		)
		(pad "3" smd custom
			(at -0.00889 0.370078 270)
			(size 0.74295 0.74295)
			(layers "F.Cu" "F.Mask" "F.Paste")
			(net "GND")
			(options
				(clearance outline)
				(anchor circle)
			)
			(primitives
				(gr_poly
					(pts
						(xy -2.1209 1.4859) (xy 2.1209 1.4859) (xy 2.1209 -1.4859) (xy 1.08585 -1.4859) (xy 1.08585 -0.4699)
						(xy -1.08585 -0.4699) (xy -1.08585 -1.4859) (xy -2.1209 -1.4859)
					)
					(width 0)
					(fill yes)
				)
			)
		)
		(pad "4" thru_hole circle
			(at 1.266444 -3.851656 270)
			(size 1.4478 1.4478)
			(drill 1.0414)
			(layers "*.Cu" "*.Mask")
			(remove_unused_layers no)
			(net "GND")
			(clearance 0.1524)
			(thermal_gap 0.1524)
		)
		(pad "5" thru_hole circle
			(at -1.273556 -3.851656 270)
			(size 1.4478 1.4478)
			(drill 1.0414)
			(layers "*.Cu" "*.Mask")
			(remove_unused_layers no)
			(net "GND")
			(clearance 0.1524)
			(thermal_gap 0.1524)
		)
		(pad "6" thru_hole circle
			(at 1.266444 2.498344 270)
			(size 1.4478 1.4478)
			(drill 1.0414)
			(layers "*.Cu" "*.Mask")
			(remove_unused_layers no)
			(net "GND")
			(clearance 0.1524)
			(thermal_gap 0.1524)
		)
		(pad "7" thru_hole circle
			(at -1.273556 2.498344 270)
			(size 1.4478 1.4478)
			(drill 1.0414)
			(layers "*.Cu" "*.Mask")
			(remove_unused_layers no)
			(net "GND")
			(clearance 0.1524)
			(thermal_gap 0.1524)
		)
		(pad "8" thru_hole circle
			(at 1.27 -0.4572 270)
			(size 0.7112 0.7112)
			(drill 0.4064)
			(layers "*.Cu" "*.Mask")
			(remove_unused_layers no)
			(net "GND")
			(clearance 0.1016)
			(thermal_gap 0.1016)
		)
		(pad "9" thru_hole circle
			(at 1.27 0.762 270)
			(size 0.7112 0.7112)
			(drill 0.4064)
			(layers "*.Cu" "*.Mask")
			(remove_unused_layers no)
			(net "GND")
			(clearance 0.1016)
			(thermal_gap 0.1016)
		)
		(pad "10" thru_hole circle
			(at -0.0254 0.762 270)
			(size 0.7112 0.7112)
			(drill 0.4064)
			(layers "*.Cu" "*.Mask")
			(remove_unused_layers no)
			(net "GND")
			(clearance 0.1016)
			(thermal_gap 0.1016)
		)
		(pad "11" thru_hole circle
			(at -1.27 0.762 270)
			(size 0.7112 0.7112)
			(drill 0.4064)
			(layers "*.Cu" "*.Mask")
			(remove_unused_layers no)
			(net "GND")
			(clearance 0.1016)
			(thermal_gap 0.1016)
		)
		(pad "12" thru_hole circle
			(at -1.27 -0.4572 270)
			(size 0.7112 0.7112)
			(drill 0.4064)
			(layers "*.Cu" "*.Mask")
			(remove_unused_layers no)
			(net "GND")
			(clearance 0.1016)
			(thermal_gap 0.1016)
		)
	)
	(footprint ""
		(layer "F.Cu")
		(at 176.437798 -17.65681 90)
		(property "Reference" "R4F6"
			(at 0 0 90)
			(layer "F.SilkS")
			(hide yes)
			(effects
				(font
					(size 1.27 1.27)
				)
			)
		)
		(property "Value" ""
			(at 0 0 90)
			(layer "F.Fab")
			(effects
				(font
					(size 1.27 1.27)
				)
			)
		)
		(duplicate_pad_numbers_are_jumpers no)
		(fp_rect
			(start -0.2794 -0.1016)
			(end 0.2794 0.9906)
			(stroke
				(width 0)
				(type default)
			)
			(fill no)
			(layer "F.CrtYd")
		)
		(fp_line
			(start 0.2794 -0.1016)
			(end -0.2794 -0.1016)
			(stroke
				(width 0.1)
				(type default)
			)
			(layer "F.Fab")
		)
		(fp_line
			(start -0.2794 -0.1016)
			(end -0.2794 0.9906)
			(stroke
				(width 0.1)
				(type default)
			)
			(layer "F.Fab")
		)
		(fp_line
			(start 0.2794 0.9906)
			(end 0.2794 -0.1016)
			(stroke
				(width 0.1)
				(type default)
			)
			(layer "F.Fab")
		)
		(fp_line
			(start -0.2794 0.9906)
			(end 0.2794 0.9906)
			(stroke
				(width 0.1)
				(type default)
			)
			(layer "F.Fab")
		)
		(pad "1" smd rect
			(at 0 0 90)
			(size 0.508 0.508)
			(layers "F.Cu" "F.Mask" "F.Paste")
			(net "VR_PVPP_GHJ_SNUB")
		)
		(pad "2" smd rect
			(at 0 0.889 90)
			(size 0.508 0.508)
			(layers "F.Cu" "F.Mask" "F.Paste")
			(net "GND")
		)
		(zone
			(layer "F.Cu")
			(hatch none 0.5)
			(connect_pads
				(clearance 0)
			)
			(min_thickness 0.25)
			(keepout
				(tracks allowed)
				(vias not_allowed)
				(pads allowed)
				(copperpour not_allowed)
				(footprints allowed)
			)
			(placement
				(enabled no)
				(sheetname "")
			)
			(fill
				(thermal_gap 0.5)
				(thermal_bridge_width 0.5)
				(island_removal_mode 0)
			)
			(polygon
				(pts
					(xy 176.691798 -17.40281) (xy 177.072798 -17.40281) (xy 177.072798 -17.91081) (xy 176.691798 -17.91081)
				)
			)
		)
		(zone
			(layer "F.Cu")
			(hatch none 0.5)
			(connect_pads
				(clearance 0)
			)
			(min_thickness 0.25)
			(keepout
				(tracks not_allowed)
				(vias allowed)
				(pads allowed)
				(copperpour not_allowed)
				(footprints allowed)
			)
			(placement
				(enabled no)
				(sheetname "")
			)
			(fill
				(thermal_gap 0.5)
				(thermal_bridge_width 0.5)
				(island_removal_mode 0)
			)
			(polygon
				(pts
					(xy 176.691798 -17.40281) (xy 177.072798 -17.40281) (xy 177.072798 -17.91081) (xy 176.691798 -17.91081)
				)
			)
		)
	)
)
